# BASEBOARD_FAB2 (Tioga Pass) — schematic netlist excerpt (pin names and nets, part order shuffled) for the footprints in the layout excerpt that follows; sources: Cadence DE-HDL packaged netlist, KiCad conversion of Wiwynn_Tioga_Pass_MB.brd

C22W30  SC22U16V5MX-4-GP  20%  pkg SMD-BCG5  page 212 : \1\ = VR_FET_SW_P12V_STBY_PVCCIO_CPU0 ; \2\ = GND
R25W43  120R2F-GP  1%  pkg RCL_GP  page 151 : \1\ = BMC_M_A5 ; \2\ = P1V2_AUX_BMC

U1M2  NC7SB3157  IC  pkg SMLF  page 113
  B1  = JTAG_MCP_CPU0_TDO
  GND  = GND
  B0  = JTAG_MCP_CPU1_TDO
  A  = JTAG_MCP_MUX_TDO
  VCC  = P3V3_STBY
  S  = FM_CPU1_CD_PRES_N

(kicad_pcb
	(version 20260206)
	(generator "pcbnew")
	(generator_version "10.0")
	(general
		(thickness 1.6)
		(legacy_teardrops no)
	)
	(paper "A4")
	(title_block
		(title "Wiwynn_Tioga_Pass_MB.brd")
		(comment 1 "Tioga Pass / footprints 4420-4422 of 4770")
	)
	(layers
		(0 "F.Cu" signal "TOP")
		(4 "In1.Cu" signal "L2GND")
		(6 "In2.Cu" signal "L3")
		(8 "In3.Cu" signal "L4GND")
		(10 "In4.Cu" signal "L5")
		(12 "In5.Cu" signal "L6GND")
		(14 "In6.Cu" signal "L7VCC")
		(16 "In7.Cu" signal "L8VCC")
		(18 "In8.Cu" signal "L9GND")
		(20 "In9.Cu" signal "L10")
		(22 "In10.Cu" signal "L11GND")
		(24 "In11.Cu" signal "L12")
		(26 "In12.Cu" signal "L13GND")
		(2 "B.Cu" signal "BOTTOM")
		(9 "F.Adhes" user "F.Adhesive")
		(11 "B.Adhes" user "B.Adhesive")
		(13 "F.Paste" user "Package Geometry/Pastemask Top")
		(15 "B.Paste" user "Package Geometry/Pastemask Bottom")
		(5 "F.SilkS" user "Ref Des/Silkscreen Top")
		(7 "B.SilkS" user "Ref Des/Silkscreen Bottom")
		(1 "F.Mask" user "Board Geometry/Soldermask Top")
		(3 "B.Mask" user "Board Geometry/Soldermask Bottom")
		(17 "Dwgs.User" user "User.Drawings")
		(19 "Cmts.User" user "User.Comments")
		(21 "Eco1.User" user "User.Eco1")
		(23 "Eco2.User" user "User.Eco2")
		(25 "Edge.Cuts" user "Board Geometry/Outline")
		(27 "Margin" user)
		(31 "F.CrtYd" user "Package Geometry/Place Bound Top")
		(29 "B.CrtYd" user "Package Geometry/Place Bound Bottom")
		(35 "F.Fab" user "Ref Des/Assembly Top")
		(33 "B.Fab" user "Ref Des/Assembly Bottom")
	)
	(footprint ""
		(layer "B.Cu")
		(at 348.488 -104.267 180)
		(property "Reference" "C22W30"
			(at 0 0 0)
			(layer "B.SilkS")
			(hide yes)
			(effects
				(font
					(size 1.27 1.27)
				)
				(justify mirror)
			)
		)
		(property "Value" "*"
			(at 0.0762 -6.2357 180)
			(unlocked yes)
			(layer "B.Fab")
			(hide yes)
			(effects
				(font
					(size 1.27 1.016)
					(thickness 0.1524)
				)
				(justify mirror)
			)
		)
		(property "Device Type" "SC22U16V5MX-4-GP_SMD-BCG5-SC22A"
			(at 0.0762 -8.2677 180)
			(unlocked yes)
			(layer "B.Fab")
			(hide yes)
			(effects
				(font
					(size 1.27 1.016)
					(thickness 0.1524)
				)
				(justify mirror)
			)
		)
		(duplicate_pad_numbers_are_jumpers no)
		(fp_line
			(start -0.635 0)
			(end 0.635 0)
			(stroke
				(width 0.508)
				(type default)
			)
			(layer "B.SilkS")
		)
		(fp_rect
			(start 0.9652 1.778)
			(end -0.9652 -1.778)
			(stroke
				(width 0)
				(type default)
			)
			(fill no)
			(layer "B.CrtYd")
		)
		(fp_poly
			(pts
				(xy 0.9652 -1.778) (xy -0.9652 -1.778) (xy -0.9652 1.778) (xy 0.9652 1.778)
			)
			(stroke
				(width 0)
				(type default)
			)
			(fill no)
			(layer "B.Fab")
		)
		(pad "1" smd rect
			(at 0 -0.9652)
			(size 1.397 1.143)
			(layers "B.Cu" "B.Mask" "B.Paste")
			(net "VR_FET_SW_P12V_STBY_PVCCIO_CPU0")
		)
		(pad "2" smd rect
			(at 0 0.9652)
			(size 1.397 1.143)
			(layers "B.Cu" "B.Mask" "B.Paste")
			(net "GND")
		)
	)
	(footprint ""
		(layer "B.Cu")
		(at 436.547006 -43.54195 180)
		(property "Reference" "R25W43"
			(at 0 0 0)
			(layer "B.SilkS")
			(hide yes)
			(effects
				(font
					(size 1.27 1.27)
				)
				(justify mirror)
			)
		)
		(property "Value" "*"
			(at -0.064008 -4.108196 180)
			(unlocked yes)
			(layer "B.Fab")
			(hide yes)
			(effects
				(font
					(size 1.27 1.016)
					(thickness 0.1524)
				)
				(justify mirror)
			)
		)
		(property "Device Type" "120R2F-GP_RCL_GP-120R2F-GP,64.A"
			(at -0.064008 -5.632196 180)
			(unlocked yes)
			(layer "B.Fab")
			(hide yes)
			(effects
				(font
					(size 1.27 1.016)
					(thickness 0.1524)
				)
				(justify mirror)
			)
		)
		(duplicate_pad_numbers_are_jumpers no)
		(fp_line
			(start 0.508 -0.9398)
			(end 0.508 0.9398)
			(stroke
				(width 0.1524)
				(type default)
			)
			(layer "B.SilkS")
		)
		(fp_line
			(start -0.508 -0.9398)
			(end 0.508 -0.9398)
			(stroke
				(width 0.1524)
				(type default)
			)
			(layer "B.SilkS")
		)
		(fp_rect
			(start 0.508 0.9398)
			(end -0.508 -0.9398)
			(stroke
				(width 0)
				(type default)
			)
			(fill no)
			(layer "B.CrtYd")
		)
		(fp_rect
			(start 0.508 0.9398)
			(end -0.508 -0.9398)
			(stroke
				(width 0)
				(type default)
			)
			(fill no)
			(layer "B.Fab")
		)
		(pad "1" smd custom
			(at 0 -0.4445)
			(size 0.1397 0.1397)
			(layers "B.Cu" "B.Mask" "B.Paste")
			(net "BMC_M_A5")
			(options
				(clearance outline)
				(anchor circle)
			)
			(primitives
				(gr_poly
					(pts
						(arc
							(start -0.1778 0.2794)
							(mid -0.249642 0.249642)
							(end -0.2794 0.1778)
						)
						(arc
							(start -0.2794 -0.1778)
							(mid -0.249642 -0.249642)
							(end -0.1778 -0.2794)
						)
						(arc
							(start 0.1778 -0.2794)
							(mid 0.249642 -0.249642)
							(end 0.2794 -0.1778)
						)
						(arc
							(start 0.2794 0.1778)
							(mid 0.249642 0.249642)
							(end 0.1778 0.2794)
						)
					)
					(width 0)
					(fill yes)
				)
			)
		)
		(pad "2" smd custom
			(at 0 0.4445)
			(size 0.1397 0.1397)
			(layers "B.Cu" "B.Mask" "B.Paste")
			(net "P1V2_AUX_BMC")
			(options
				(clearance outline)
				(anchor circle)
			)
			(primitives
				(gr_poly
					(pts
						(arc
							(start -0.1778 0.2794)
							(mid -0.249642 0.249642)
							(end -0.2794 0.1778)
						)
						(arc
							(start -0.2794 -0.1778)
							(mid -0.249642 -0.249642)
							(end -0.1778 -0.2794)
						)
						(arc
							(start 0.1778 -0.2794)
							(mid 0.249642 -0.249642)
							(end 0.2794 -0.1778)
						)
						(arc
							(start 0.2794 0.1778)
							(mid 0.249642 0.249642)
							(end 0.1778 0.2794)
						)
					)
					(width 0)
					(fill yes)
				)
			)
		)
	)
	(footprint ""
		(layer "B.Cu")
		(at 495.01552 -133.6675 90)
		(property "Reference" "U1M2"
			(at -3.14198 -1.37541 270)
			(unlocked yes)
			(layer "B.SilkS")
			(effects
				(font
					(size 0.7874 0.5842)
					(thickness 0.1524)
				)
				(justify left mirror)
			)
		)
		(property "Value" ""
			(at 0 0 90)
			(layer "B.Fab")
			(effects
				(font
					(size 1.27 1.27)
				)
				(justify mirror)
			)
		)
		(duplicate_pad_numbers_are_jumpers no)
		(fp_circle
			(center 0.595884 -0.655574)
			(end 0.595884 -0.528574)
			(stroke
				(width 0.254)
				(type default)
			)
			(fill no)
			(layer "B.SilkS")
		)
		(fp_poly
			(pts
				(xy -0.21463 -0.450088) (xy -1.56337 -0.450088) (xy -1.56337 1.75006) (xy -0.21463 1.75006)
			)
			(stroke
				(width 0)
				(type default)
			)
			(fill no)
			(layer "B.CrtYd")
		)
		(fp_line
			(start -0.21463 -0.450088)
			(end -1.56337 -0.450088)
			(stroke
				(width 0.1)
				(type default)
			)
			(layer "B.Fab")
		)
		(fp_line
			(start -1.56337 -0.450088)
			(end -1.56337 1.75006)
			(stroke
				(width 0.1)
				(type default)
			)
			(layer "B.Fab")
		)
		(fp_line
			(start -0.21463 1.75006)
			(end -0.21463 -0.450088)
			(stroke
				(width 0.1)
				(type default)
			)
			(layer "B.Fab")
		)
		(fp_line
			(start -1.56337 1.75006)
			(end -0.21463 1.75006)
			(stroke
				(width 0.1)
				(type default)
			)
			(layer "B.Fab")
		)
		(fp_circle
			(center 0.848614 -0.6477)
			(end 0.848614 -0.5207)
			(stroke
				(width 0.254)
				(type default)
			)
			(fill no)
			(layer "B.Fab")
		)
		(pad "1" smd rect
			(at 0 0 270)
			(size 1.016 0.381)
			(layers "B.Cu" "B.Mask" "B.Paste")
			(net "JTAG_MCP_CPU0_TDO")
		)
		(pad "2" smd rect
			(at 0 0.649986 270)
			(size 1.016 0.381)
			(layers "B.Cu" "B.Mask" "B.Paste")
			(net "GND")
		)
		(pad "3" smd rect
			(at 0 1.299972 270)
			(size 1.016 0.381)
			(layers "B.Cu" "B.Mask" "B.Paste")
			(net "JTAG_MCP_CPU1_TDO")
		)
		(pad "4" smd rect
			(at -1.778 1.299972 270)
			(size 1.016 0.381)
			(layers "B.Cu" "B.Mask" "B.Paste")
			(net "JTAG_MCP_MUX_TDO")
		)
		(pad "5" smd rect
			(at -1.778 0.649986 270)
			(size 1.016 0.381)
			(layers "B.Cu" "B.Mask" "B.Paste")
			(net "P3V3_STBY")
		)
		(pad "6" smd rect
			(at -1.778 0 270)
			(size 1.016 0.381)
			(layers "B.Cu" "B.Mask" "B.Paste")
			(net "FM_CPU1_CD_PRES_N")
		)
	)
)
